(kicad_sch (version 20211123) (generator eeschema)

  (paper "A3")

  (title_block
    (title "SA800U (Snapdragon 845) Baseboard")
    (date "2023-10-19")
    (rev "1.0.3")
    (company "Antmicro Ltd.")
    (comment 1 "www.antmicro.com")
  )

  (junction (at 131.699 70.866) (diameter 0) (color 0 0 0 0)
  )
  (junction (at 160.274 88.646) (diameter 0) (color 0 0 0 0)
  )
  (junction (at 129.159 68.326) (diameter 0) (color 0 0 0 0)
  )
  (junction (at 84.582 148.082) (diameter 0) (color 0 0 0 0)
  )
  (junction (at 152.527 158.242) (diameter 0) (color 0 0 0 0)
  )
  (junction (at 152.527 148.082) (diameter 0) (color 0 0 0 0)
  )
  (junction (at 108.077 158.242) (diameter 0) (color 0 0 0 0)
  )
  (junction (at 136.779 75.946) (diameter 0) (color 0 0 0 0)
  )
  (junction (at 172.339 93.726) (diameter 0) (color 0 0 0 0)
  )
  (junction (at 105.537 160.782) (diameter 0) (color 0 0 0 0)
  )
  (junction (at 152.654 78.486) (diameter 0) (color 0 0 0 0)
  )
  (junction (at 155.067 160.782) (diameter 0) (color 0 0 0 0)
  )
  (junction (at 116.967 155.702) (diameter 0) (color 0 0 0 0)
  )
  (junction (at 157.734 86.106) (diameter 0) (color 0 0 0 0)
  )
  (junction (at 134.239 73.406) (diameter 0) (color 0 0 0 0)
  )
  (junction (at 154.559 54.991) (diameter 0) (color 0 0 0 0)
  )
  (junction (at 92.329 68.326) (diameter 0) (color 0 0 0 0)
  )
  (junction (at 176.022 148.082) (diameter 0) (color 0 0 0 0)
  )
  (junction (at 155.194 81.026) (diameter 0) (color 0 0 0 0)
  )
  (junction (at 155.067 148.082) (diameter 0) (color 0 0 0 0)
  )

  (no_connect (at 224.917 147.447))

  (wire (pts (xy 101.981 78.486) (xy 152.654 78.486))
    (stroke (width 0) (type default) (color 0 0 0 0))
  )
  (wire (pts (xy 116.967 163.322) (xy 116.967 155.702))
    (stroke (width 0) (type default) (color 0 0 0 0))
  )
  (wire (pts (xy 96.901 78.486) (xy 91.694 78.486))
    (stroke (width 0) (type default) (color 0 0 0 0))
  )
  (wire (pts (xy 134.239 73.406) (xy 173.609 73.406))
    (stroke (width 0) (type default) (color 0 0 0 0))
  )
  (wire (pts (xy 101.981 70.866) (xy 131.699 70.866))
    (stroke (width 0) (type default) (color 0 0 0 0))
  )
  (wire (pts (xy 165.354 54.991) (xy 165.354 57.531))
    (stroke (width 0) (type default) (color 0 0 0 0))
  )
  (wire (pts (xy 96.901 86.106) (xy 91.694 86.106))
    (stroke (width 0) (type default) (color 0 0 0 0))
  )
  (wire (pts (xy 176.022 148.082) (xy 176.022 149.352))
    (stroke (width 0) (type default) (color 0 0 0 0))
  )
  (wire (pts (xy 136.779 94.996) (xy 136.779 75.946))
    (stroke (width 0) (type default) (color 0 0 0 0))
  )
  (wire (pts (xy 96.901 68.326) (xy 92.329 68.326))
    (stroke (width 0) (type default) (color 0 0 0 0))
  )
  (wire (pts (xy 143.637 148.082) (xy 152.527 148.082))
    (stroke (width 0) (type default) (color 0 0 0 0))
  )
  (wire (pts (xy 118.999 93.726) (xy 126.619 93.726))
    (stroke (width 0) (type default) (color 0 0 0 0))
  )
  (wire (pts (xy 169.164 91.186) (xy 173.609 91.186))
    (stroke (width 0) (type default) (color 0 0 0 0))
  )
  (wire (pts (xy 101.981 75.946) (xy 136.779 75.946))
    (stroke (width 0) (type default) (color 0 0 0 0))
  )
  (wire (pts (xy 157.734 94.996) (xy 157.734 86.106))
    (stroke (width 0) (type default) (color 0 0 0 0))
  )
  (wire (pts (xy 92.329 58.166) (xy 92.329 59.436))
    (stroke (width 0) (type default) (color 0 0 0 0))
  )
  (wire (pts (xy 101.727 158.242) (xy 108.077 158.242))
    (stroke (width 0) (type default) (color 0 0 0 0))
  )
  (wire (pts (xy 96.901 75.946) (xy 91.694 75.946))
    (stroke (width 0) (type default) (color 0 0 0 0))
  )
  (wire (pts (xy 172.339 93.726) (xy 173.609 93.726))
    (stroke (width 0) (type default) (color 0 0 0 0))
  )
  (polyline (pts (xy 390.144 126.492) (xy 19.177 126.492))
    (stroke (width 0) (type default) (color 0 0 0 0))
  )

  (wire (pts (xy 136.779 75.946) (xy 173.609 75.946))
    (stroke (width 0) (type default) (color 0 0 0 0))
  )
  (wire (pts (xy 108.077 158.242) (xy 120.142 158.242))
    (stroke (width 0) (type default) (color 0 0 0 0))
  )
  (wire (pts (xy 105.537 163.322) (xy 105.537 160.782))
    (stroke (width 0) (type default) (color 0 0 0 0))
  )
  (wire (pts (xy 152.527 148.082) (xy 155.067 148.082))
    (stroke (width 0) (type default) (color 0 0 0 0))
  )
  (wire (pts (xy 155.194 94.996) (xy 155.194 81.026))
    (stroke (width 0) (type default) (color 0 0 0 0))
  )
  (wire (pts (xy 143.129 54.991) (xy 154.559 54.991))
    (stroke (width 0) (type default) (color 0 0 0 0))
  )
  (wire (pts (xy 155.067 149.098) (xy 155.067 148.082))
    (stroke (width 0) (type default) (color 0 0 0 0))
  )
  (wire (pts (xy 150.114 94.996) (xy 150.114 93.726))
    (stroke (width 0) (type default) (color 0 0 0 0))
  )
  (wire (pts (xy 160.274 94.996) (xy 160.274 88.646))
    (stroke (width 0) (type default) (color 0 0 0 0))
  )
  (wire (pts (xy 219.202 155.067) (xy 224.917 155.067))
    (stroke (width 0) (type default) (color 0 0 0 0))
  )
  (wire (pts (xy 101.981 86.106) (xy 157.734 86.106))
    (stroke (width 0) (type default) (color 0 0 0 0))
  )
  (wire (pts (xy 143.637 155.702) (xy 140.462 155.702))
    (stroke (width 0) (type default) (color 0 0 0 0))
  )
  (wire (pts (xy 140.462 158.242) (xy 152.527 158.242))
    (stroke (width 0) (type default) (color 0 0 0 0))
  )
  (wire (pts (xy 169.164 68.326) (xy 169.164 91.186))
    (stroke (width 0) (type default) (color 0 0 0 0))
  )
  (wire (pts (xy 108.077 163.322) (xy 108.077 158.242))
    (stroke (width 0) (type default) (color 0 0 0 0))
  )
  (wire (pts (xy 142.494 93.726) (xy 142.494 98.171))
    (stroke (width 0) (type default) (color 0 0 0 0))
  )
  (wire (pts (xy 143.637 148.082) (xy 143.637 155.702))
    (stroke (width 0) (type default) (color 0 0 0 0))
  )
  (wire (pts (xy 152.654 94.996) (xy 152.654 78.486))
    (stroke (width 0) (type default) (color 0 0 0 0))
  )
  (wire (pts (xy 120.142 160.782) (xy 105.537 160.782))
    (stroke (width 0) (type default) (color 0 0 0 0))
  )
  (wire (pts (xy 152.527 163.322) (xy 152.527 158.242))
    (stroke (width 0) (type default) (color 0 0 0 0))
  )
  (wire (pts (xy 224.917 149.987) (xy 209.677 149.987))
    (stroke (width 0) (type default) (color 0 0 0 0))
  )
  (wire (pts (xy 224.917 157.607) (xy 223.647 157.607))
    (stroke (width 0) (type default) (color 0 0 0 0))
  )
  (wire (pts (xy 223.647 157.607) (xy 223.647 158.877))
    (stroke (width 0) (type default) (color 0 0 0 0))
  )
  (wire (pts (xy 92.329 64.516) (xy 92.329 68.326))
    (stroke (width 0) (type default) (color 0 0 0 0))
  )
  (wire (pts (xy 172.339 93.726) (xy 172.339 96.266))
    (stroke (width 0) (type default) (color 0 0 0 0))
  )
  (wire (pts (xy 120.142 163.322) (xy 116.967 163.322))
    (stroke (width 0) (type default) (color 0 0 0 0))
  )
  (wire (pts (xy 126.619 94.996) (xy 126.619 93.726))
    (stroke (width 0) (type default) (color 0 0 0 0))
  )
  (wire (pts (xy 155.067 160.782) (xy 171.577 160.782))
    (stroke (width 0) (type default) (color 0 0 0 0))
  )
  (wire (pts (xy 154.559 57.531) (xy 154.559 54.991))
    (stroke (width 0) (type default) (color 0 0 0 0))
  )
  (wire (pts (xy 154.559 54.991) (xy 165.354 54.991))
    (stroke (width 0) (type default) (color 0 0 0 0))
  )
  (wire (pts (xy 152.654 78.486) (xy 173.609 78.486))
    (stroke (width 0) (type default) (color 0 0 0 0))
  )
  (wire (pts (xy 116.967 155.702) (xy 120.142 155.702))
    (stroke (width 0) (type default) (color 0 0 0 0))
  )
  (wire (pts (xy 129.159 68.326) (xy 169.164 68.326))
    (stroke (width 0) (type default) (color 0 0 0 0))
  )
  (wire (pts (xy 116.967 148.082) (xy 116.967 155.702))
    (stroke (width 0) (type default) (color 0 0 0 0))
  )
  (wire (pts (xy 140.462 163.322) (xy 141.732 163.322))
    (stroke (width 0) (type default) (color 0 0 0 0))
  )
  (wire (pts (xy 105.537 160.782) (xy 101.727 160.782))
    (stroke (width 0) (type default) (color 0 0 0 0))
  )
  (wire (pts (xy 209.677 152.527) (xy 224.917 152.527))
    (stroke (width 0) (type default) (color 0 0 0 0))
  )
  (wire (pts (xy 215.519 93.726) (xy 215.519 94.996))
    (stroke (width 0) (type default) (color 0 0 0 0))
  )
  (wire (pts (xy 101.981 81.026) (xy 155.194 81.026))
    (stroke (width 0) (type default) (color 0 0 0 0))
  )
  (wire (pts (xy 155.067 163.322) (xy 155.067 160.782))
    (stroke (width 0) (type default) (color 0 0 0 0))
  )
  (wire (pts (xy 96.901 70.866) (xy 91.694 70.866))
    (stroke (width 0) (type default) (color 0 0 0 0))
  )
  (wire (pts (xy 154.559 54.356) (xy 154.559 54.991))
    (stroke (width 0) (type default) (color 0 0 0 0))
  )
  (wire (pts (xy 87.249 58.166) (xy 92.329 58.166))
    (stroke (width 0) (type default) (color 0 0 0 0))
  )
  (wire (pts (xy 186.182 148.082) (xy 176.022 148.082))
    (stroke (width 0) (type default) (color 0 0 0 0))
  )
  (wire (pts (xy 96.901 73.406) (xy 91.694 73.406))
    (stroke (width 0) (type default) (color 0 0 0 0))
  )
  (wire (pts (xy 140.462 160.782) (xy 155.067 160.782))
    (stroke (width 0) (type default) (color 0 0 0 0))
  )
  (wire (pts (xy 214.249 93.726) (xy 215.519 93.726))
    (stroke (width 0) (type default) (color 0 0 0 0))
  )
  (wire (pts (xy 92.329 68.326) (xy 91.694 68.326))
    (stroke (width 0) (type default) (color 0 0 0 0))
  )
  (wire (pts (xy 157.734 86.106) (xy 173.609 86.106))
    (stroke (width 0) (type default) (color 0 0 0 0))
  )
  (wire (pts (xy 101.981 88.646) (xy 160.274 88.646))
    (stroke (width 0) (type default) (color 0 0 0 0))
  )
  (wire (pts (xy 172.339 83.566) (xy 172.339 93.726))
    (stroke (width 0) (type default) (color 0 0 0 0))
  )
  (wire (pts (xy 155.067 148.082) (xy 176.022 148.082))
    (stroke (width 0) (type default) (color 0 0 0 0))
  )
  (wire (pts (xy 160.274 88.646) (xy 173.609 88.646))
    (stroke (width 0) (type default) (color 0 0 0 0))
  )
  (wire (pts (xy 131.699 70.866) (xy 173.609 70.866))
    (stroke (width 0) (type default) (color 0 0 0 0))
  )
  (wire (pts (xy 78.232 148.082) (xy 84.582 148.082))
    (stroke (width 0) (type default) (color 0 0 0 0))
  )
  (wire (pts (xy 142.494 93.726) (xy 150.114 93.726))
    (stroke (width 0) (type default) (color 0 0 0 0))
  )
  (wire (pts (xy 155.194 81.026) (xy 173.609 81.026))
    (stroke (width 0) (type default) (color 0 0 0 0))
  )
  (wire (pts (xy 152.527 154.178) (xy 152.527 158.242))
    (stroke (width 0) (type default) (color 0 0 0 0))
  )
  (wire (pts (xy 173.609 83.566) (xy 172.339 83.566))
    (stroke (width 0) (type default) (color 0 0 0 0))
  )
  (wire (pts (xy 129.159 68.326) (xy 129.159 94.996))
    (stroke (width 0) (type default) (color 0 0 0 0))
  )
  (wire (pts (xy 101.981 73.406) (xy 134.239 73.406))
    (stroke (width 0) (type default) (color 0 0 0 0))
  )
  (wire (pts (xy 134.239 94.996) (xy 134.239 73.406))
    (stroke (width 0) (type default) (color 0 0 0 0))
  )
  (wire (pts (xy 118.999 93.726) (xy 118.999 98.171))
    (stroke (width 0) (type default) (color 0 0 0 0))
  )
  (polyline (pts (xy 21.082 44.069) (xy 399.796 44.069))
    (stroke (width 0) (type default) (color 0 0 0 0))
  )

  (wire (pts (xy 101.981 68.326) (xy 129.159 68.326))
    (stroke (width 0) (type default) (color 0 0 0 0))
  )
  (wire (pts (xy 84.582 148.082) (xy 84.582 149.352))
    (stroke (width 0) (type default) (color 0 0 0 0))
  )
  (wire (pts (xy 84.582 148.082) (xy 116.967 148.082))
    (stroke (width 0) (type default) (color 0 0 0 0))
  )
  (wire (pts (xy 96.901 81.026) (xy 91.694 81.026))
    (stroke (width 0) (type default) (color 0 0 0 0))
  )
  (wire (pts (xy 152.527 158.242) (xy 171.577 158.242))
    (stroke (width 0) (type default) (color 0 0 0 0))
  )
  (wire (pts (xy 141.732 163.322) (xy 141.732 164.592))
    (stroke (width 0) (type default) (color 0 0 0 0))
  )
  (wire (pts (xy 131.699 94.996) (xy 131.699 70.866))
    (stroke (width 0) (type default) (color 0 0 0 0))
  )
  (wire (pts (xy 152.527 149.098) (xy 152.527 148.082))
    (stroke (width 0) (type default) (color 0 0 0 0))
  )
  (wire (pts (xy 96.901 88.646) (xy 91.694 88.646))
    (stroke (width 0) (type default) (color 0 0 0 0))
  )
  (wire (pts (xy 155.067 154.178) (xy 155.067 160.782))
    (stroke (width 0) (type default) (color 0 0 0 0))
  )

  (text "Other interfaces" (at 22.987 25.019 0)
    (effects (font (size 2.9972 2.9972) (thickness 0.5994) bold) (justify left bottom))
  )
  (text "I2C" (at 20.447 131.572 0)
    (effects (font (size 2.54 2.54)) (justify left bottom))
  )
  (text "Text" (at 67.7926 1253.8202 0)
    (effects (font (size 1.524 1.524)) (justify left bottom))
  )
  (text "Text" (at 67.7926 1253.8202 0)
    (effects (font (size 1.524 1.524)) (justify left bottom))
  )
  (text "Note:\nPullups on SoM.sch" (at 97.282 153.162 0)
    (effects (font (size 1.27 1.27)) (justify left bottom))
  )
  (text "uSD" (at 22.352 49.149 0)
    (effects (font (size 2.54 2.54)) (justify left bottom))
  )

  (label "I2C10_SDA_3V3" (at 209.677 152.527 0)
    (effects (font (size 1.27 1.27)) (justify left bottom))
  )
  (label "SD_VDD_R" (at 112.014 78.486 0)
    (effects (font (size 1.27 1.27)) (justify left bottom))
  )
  (label "SD_CMD_R" (at 112.014 75.946 0)
    (effects (font (size 1.27 1.27)) (justify left bottom))
  )
  (label "SD_DATA1_R" (at 112.014 88.646 0)
    (effects (font (size 1.27 1.27)) (justify left bottom))
  )
  (label "I2C10_SDA_3V3" (at 171.577 160.782 180)
    (effects (font (size 1.27 1.27)) (justify right bottom))
  )
  (label "I2C10_SCL_3V3" (at 209.677 149.987 0)
    (effects (font (size 1.27 1.27)) (justify left bottom))
  )
  (label "SD_DET_R" (at 112.014 68.326 0)
    (effects (font (size 1.27 1.27)) (justify left bottom))
  )
  (label "SD_DATA0_R" (at 112.014 86.106 0)
    (effects (font (size 1.27 1.27)) (justify left bottom))
  )
  (label "I2C10_SCL_3V3" (at 171.577 158.242 180)
    (effects (font (size 1.27 1.27)) (justify right bottom))
  )
  (label "SD_DATA2_R" (at 112.014 70.866 0)
    (effects (font (size 1.27 1.27)) (justify left bottom))
  )
  (label "SD_CLK_R" (at 112.014 81.026 0)
    (effects (font (size 1.27 1.27)) (justify left bottom))
  )
  (label "SD_VDD_R" (at 143.129 54.991 0)
    (effects (font (size 1.27 1.27)) (justify left bottom))
  )
  (label "SD_DATA3_R" (at 112.014 73.406 0)
    (effects (font (size 1.27 1.27)) (justify left bottom))
  )

  (global_label "3V3_SYS" (shape input) (at 219.202 155.067 180) (fields_autoplaced)
    (effects (font (size 1.27 1.27)) (justify right))
    (property "Intersheet References" "${INTERSHEET_REFS}" (id 0) (at 6.477 17.907 0)
      (effects (font (size 1.27 1.27)) hide)
    )
  )
  (global_label "SD_LDO21A" (shape input) (at 91.694 78.486 180) (fields_autoplaced)
    (effects (font (size 1.27 1.27)) (justify right))
    (property "Intersheet References" "${INTERSHEET_REFS}" (id 0) (at 7.874 11.811 0)
      (effects (font (size 1.27 1.27)) hide)
    )
  )
  (global_label "SD_DATA3" (shape input) (at 91.694 73.406 180) (fields_autoplaced)
    (effects (font (size 1.27 1.27)) (justify right))
    (property "Intersheet References" "${INTERSHEET_REFS}" (id 0) (at 7.874 11.811 0)
      (effects (font (size 1.27 1.27)) hide)
    )
  )
  (global_label "SD_CLK" (shape input) (at 91.694 81.026 180) (fields_autoplaced)
    (effects (font (size 1.27 1.27)) (justify right))
    (property "Intersheet References" "${INTERSHEET_REFS}" (id 0) (at 7.874 11.811 0)
      (effects (font (size 1.27 1.27)) hide)
    )
  )
  (global_label "VREG_S4A_1V8" (shape input) (at 87.249 58.166 180) (fields_autoplaced)
    (effects (font (size 1.27 1.27)) (justify right))
    (property "Intersheet References" "${INTERSHEET_REFS}" (id 0) (at 7.874 11.811 0)
      (effects (font (size 1.27 1.27)) hide)
    )
  )
  (global_label "SD_DET" (shape input) (at 91.694 68.326 180) (fields_autoplaced)
    (effects (font (size 1.27 1.27)) (justify right))
    (property "Intersheet References" "${INTERSHEET_REFS}" (id 0) (at 7.874 11.811 0)
      (effects (font (size 1.27 1.27)) hide)
    )
  )
  (global_label "I2C10_SDA" (shape bidirectional) (at 101.727 160.782 180) (fields_autoplaced)
    (effects (font (size 1.27 1.27)) (justify right))
    (property "Intersheet References" "${INTERSHEET_REFS}" (id 0) (at 6.477 17.907 0)
      (effects (font (size 1.27 1.27)) hide)
    )
  )
  (global_label "I2C10_SCL" (shape input) (at 101.727 158.242 180) (fields_autoplaced)
    (effects (font (size 1.27 1.27)) (justify right))
    (property "Intersheet References" "${INTERSHEET_REFS}" (id 0) (at 6.477 17.907 0)
      (effects (font (size 1.27 1.27)) hide)
    )
  )
  (global_label "SD_DATA2" (shape input) (at 91.694 70.866 180) (fields_autoplaced)
    (effects (font (size 1.27 1.27)) (justify right))
    (property "Intersheet References" "${INTERSHEET_REFS}" (id 0) (at 7.874 11.811 0)
      (effects (font (size 1.27 1.27)) hide)
    )
  )
  (global_label "SD_CMD" (shape input) (at 91.694 75.946 180) (fields_autoplaced)
    (effects (font (size 1.27 1.27)) (justify right))
    (property "Intersheet References" "${INTERSHEET_REFS}" (id 0) (at 7.874 11.811 0)
      (effects (font (size 1.27 1.27)) hide)
    )
  )
  (global_label "VREG_S4A_1V8" (shape input) (at 78.232 148.082 180) (fields_autoplaced)
    (effects (font (size 1.27 1.27)) (justify right))
    (property "Intersheet References" "${INTERSHEET_REFS}" (id 0) (at 6.477 17.907 0)
      (effects (font (size 1.27 1.27)) hide)
    )
  )
  (global_label "3V3_SYS" (shape input) (at 186.182 148.082 0) (fields_autoplaced)
    (effects (font (size 1.27 1.27)) (justify left))
    (property "Intersheet References" "${INTERSHEET_REFS}" (id 0) (at 6.477 17.907 0)
      (effects (font (size 1.27 1.27)) hide)
    )
  )
  (global_label "SD_DATA1" (shape input) (at 91.694 88.646 180) (fields_autoplaced)
    (effects (font (size 1.27 1.27)) (justify right))
    (property "Intersheet References" "${INTERSHEET_REFS}" (id 0) (at 7.874 11.811 0)
      (effects (font (size 1.27 1.27)) hide)
    )
  )
  (global_label "SD_DATA0" (shape input) (at 91.694 86.106 180) (fields_autoplaced)
    (effects (font (size 1.27 1.27)) (justify right))
    (property "Intersheet References" "${INTERSHEET_REFS}" (id 0) (at 7.874 11.811 0)
      (effects (font (size 1.27 1.27)) hide)
    )
  )

  (symbol (lib_id "sa800u-baseboard-hw:R_33R_0402") (at 96.901 70.866 0) (unit 1)
    (in_bom yes) (on_board yes)
    (property "Reference" "R96" (id 0) (at 104.267 69.469 0)
      (effects (font (size 1.524 1.524)))
    )
    (property "Value" "R_33R_0402" (id 1) (at 96.901 74.676 0)
      (effects (font (size 1.524 1.524)) hide)
    )
    (property "Footprint" "sa800u-baseboard-hw-footprints:R_0402_1005Metric" (id 2) (at 101.981 65.786 0)
      (effects (font (size 1.524 1.524)) (justify left) hide)
    )
    (property "Datasheet" "https://www.bourns.com/docs/product-datasheets/cr.pdf" (id 3) (at 96.901 70.866 0)
      (effects (font (size 1.27 1.27)) hide)
    )
    (property "Manufacturer" "Bourns" (id 4) (at 101.981 60.706 0)
      (effects (font (size 1.524 1.524)) (justify left) hide)
    )
    (property "MPN" "CR0402-FX-33R0GLF" (id 5) (at 101.981 63.246 0)
      (effects (font (size 1.524 1.524)) (justify left) hide)
    )
    (property "Val" "33R" (id 6) (at 108.966 69.596 0))
    (property "License" "Apache-2.0" (id 7) (at 117.221 96.266 0)
      (effects (font (size 1.27 1.27) (thickness 0.15)) (justify left bottom) hide)
    )
    (property "Author" "Antmicro" (id 8) (at 117.221 98.806 0)
      (effects (font (size 1.27 1.27) (thickness 0.15)) (justify left bottom) hide)
    )
    (property "Tolerance" "1%" (id 9) (at 117.221 81.026 0)
      (effects (font (size 1.27 1.27)) (justify left bottom) hide)
    )
    (pin "1")
    (pin "2")
  )

  (symbol (lib_id "sa800u-baseboard-hw:R_33R_0402") (at 96.901 73.406 0) (unit 1)
    (in_bom yes) (on_board yes)
    (property "Reference" "R97" (id 0) (at 104.267 72.009 0)
      (effects (font (size 1.524 1.524)))
    )
    (property "Value" "R_33R_0402" (id 1) (at 96.901 77.216 0)
      (effects (font (size 1.524 1.524)) hide)
    )
    (property "Footprint" "sa800u-baseboard-hw-footprints:R_0402_1005Metric" (id 2) (at 101.981 68.326 0)
      (effects (font (size 1.524 1.524)) (justify left) hide)
    )
    (property "Datasheet" "https://www.bourns.com/docs/product-datasheets/cr.pdf" (id 3) (at 96.901 73.406 0)
      (effects (font (size 1.27 1.27)) hide)
    )
    (property "Manufacturer" "Bourns" (id 4) (at 101.981 63.246 0)
      (effects (font (size 1.524 1.524)) (justify left) hide)
    )
    (property "MPN" "CR0402-FX-33R0GLF" (id 5) (at 101.981 65.786 0)
      (effects (font (size 1.524 1.524)) (justify left) hide)
    )
    (property "Val" "33R" (id 6) (at 108.966 72.136 0))
    (property "License" "Apache-2.0" (id 7) (at 117.221 98.806 0)
      (effects (font (size 1.27 1.27) (thickness 0.15)) (justify left bottom) hide)
    )
    (property "Author" "Antmicro" (id 8) (at 117.221 101.346 0)
      (effects (font (size 1.27 1.27) (thickness 0.15)) (justify left bottom) hide)
    )
    (property "Tolerance" "1%" (id 9) (at 117.221 83.566 0)
      (effects (font (size 1.27 1.27)) (justify left bottom) hide)
    )
    (pin "1")
    (pin "2")
  )

  (symbol (lib_id "sa800u-baseboard-hw:R_33R_0402") (at 96.901 75.946 0) (unit 1)
    (in_bom yes) (on_board yes)
    (property "Reference" "R98" (id 0) (at 104.267 74.549 0)
      (effects (font (size 1.524 1.524)))
    )
    (property "Value" "R_33R_0402" (id 1) (at 96.901 79.756 0)
      (effects (font (size 1.524 1.524)) hide)
    )
    (property "Footprint" "sa800u-baseboard-hw-footprints:R_0402_1005Metric" (id 2) (at 101.981 70.866 0)
      (effects (font (size 1.524 1.524)) (justify left) hide)
    )
    (property "Datasheet" "https://www.bourns.com/docs/product-datasheets/cr.pdf" (id 3) (at 96.901 75.946 0)
      (effects (font (size 1.27 1.27)) hide)
    )
    (property "Manufacturer" "Bourns" (id 4) (at 101.981 65.786 0)
      (effects (font (size 1.524 1.524)) (justify left) hide)
    )
    (property "MPN" "CR0402-FX-33R0GLF" (id 5) (at 101.981 68.326 0)
      (effects (font (size 1.524 1.524)) (justify left) hide)
    )
    (property "Val" "33R" (id 6) (at 108.966 74.676 0))
    (property "License" "Apache-2.0" (id 7) (at 117.221 101.346 0)
      (effects (font (size 1.27 1.27) (thickness 0.15)) (justify left bottom) hide)
    )
    (property "Author" "Antmicro" (id 8) (at 117.221 103.886 0)
      (effects (font (size 1.27 1.27) (thickness 0.15)) (justify left bottom) hide)
    )
    (property "Tolerance" "1%" (id 9) (at 117.221 86.106 0)
      (effects (font (size 1.27 1.27)) (justify left bottom) hide)
    )
    (pin "1")
    (pin "2")
  )

  (symbol (lib_id "sa800u-baseboard-hw:R_33R_0402") (at 96.901 81.026 0) (unit 1)
    (in_bom yes) (on_board yes)
    (property "Reference" "R100" (id 0) (at 104.267 79.629 0)
      (effects (font (size 1.524 1.524)))
    )
    (property "Value" "R_33R_0402" (id 1) (at 96.901 84.836 0)
      (effects (font (size 1.524 1.524)) hide)
    )
    (property "Footprint" "sa800u-baseboard-hw-footprints:R_0402_1005Metric" (id 2) (at 101.981 75.946 0)
      (effects (font (size 1.524 1.524)) (justify left) hide)
    )
    (property "Datasheet" "https://www.bourns.com/docs/product-datasheets/cr.pdf" (id 3) (at 96.901 81.026 0)
      (effects (font (size 1.27 1.27)) hide)
    )
    (property "Manufacturer" "Bourns" (id 4) (at 101.981 70.866 0)
      (effects (font (size 1.524 1.524)) (justify left) hide)
    )
    (property "MPN" "CR0402-FX-33R0GLF" (id 5) (at 101.981 73.406 0)
      (effects (font (size 1.524 1.524)) (justify left) hide)
    )
    (property "Val" "33R" (id 6) (at 108.966 79.756 0))
    (property "License" "Apache-2.0" (id 7) (at 117.221 106.426 0)
      (effects (font (size 1.27 1.27) (thickness 0.15)) (justify left bottom) hide)
    )
    (property "Author" "Antmicro" (id 8) (at 117.221 108.966 0)
      (effects (font (size 1.27 1.27) (thickness 0.15)) (justify left bottom) hide)
    )
    (property "Tolerance" "1%" (id 9) (at 117.221 91.186 0)
      (effects (font (size 1.27 1.27)) (justify left bottom) hide)
    )
    (pin "1")
    (pin "2")
  )

  (symbol (lib_id "sa800u-baseboard-hw:R_33R_0402") (at 96.901 86.106 0) (unit 1)
    (in_bom yes) (on_board yes)
    (property "Reference" "R101" (id 0) (at 104.267 84.709 0)
      (effects (font (size 1.524 1.524)))
    )
    (property "Value" "R_33R_0402" (id 1) (at 96.901 89.916 0)
      (effects (font (size 1.524 1.524)) hide)
    )
    (property "Footprint" "sa800u-baseboard-hw-footprints:R_0402_1005Metric" (id 2) (at 101.981 81.026 0)
      (effects (font (size 1.524 1.524)) (justify left) hide)
    )
    (property "Datasheet" "https://www.bourns.com/docs/product-datasheets/cr.pdf" (id 3) (at 96.901 86.106 0)
      (effects (font (size 1.27 1.27)) hide)
    )
    (property "Manufacturer" "Bourns" (id 4) (at 101.981 75.946 0)
      (effects (font (size 1.524 1.524)) (justify left) hide)
    )
    (property "MPN" "CR0402-FX-33R0GLF" (id 5) (at 101.981 78.486 0)
      (effects (font (size 1.524 1.524)) (justify left) hide)
    )
    (property "Val" "33R" (id 6) (at 108.966 84.836 0))
    (property "License" "Apache-2.0" (id 7) (at 117.221 111.506 0)
      (effects (font (size 1.27 1.27) (thickness 0.15)) (justify left bottom) hide)
    )
    (property "Author" "Antmicro" (id 8) (at 117.221 114.046 0)
      (effects (font (size 1.27 1.27) (thickness 0.15)) (justify left bottom) hide)
    )
    (property "Tolerance" "1%" (id 9) (at 117.221 96.266 0)
      (effects (font (size 1.27 1.27)) (justify left bottom) hide)
    )
    (pin "1")
    (pin "2")
  )

  (symbol (lib_id "sa800u-baseboard-hw:R_33R_0402") (at 96.901 88.646 0) (unit 1)
    (in_bom yes) (on_board yes)
    (property "Reference" "R102" (id 0) (at 104.267 87.249 0)
      (effects (font (size 1.524 1.524)))
    )
    (property "Value" "R_33R_0402" (id 1) (at 96.901 92.456 0)
      (effects (font (size 1.524 1.524)) hide)
    )
    (property "Footprint" "sa800u-baseboard-hw-footprints:R_0402_1005Metric" (id 2) (at 101.981 83.566 0)
      (effects (font (size 1.524 1.524)) (justify left) hide)
    )
    (property "Datasheet" "https://www.bourns.com/docs/product-datasheets/cr.pdf" (id 3) (at 96.901 88.646 0)
      (effects (font (size 1.27 1.27)) hide)
    )
    (property "Manufacturer" "Bourns" (id 4) (at 101.981 78.486 0)
      (effects (font (size 1.524 1.524)) (justify left) hide)
    )
    (property "MPN" "CR0402-FX-33R0GLF" (id 5) (at 101.981 81.026 0)
      (effects (font (size 1.524 1.524)) (justify left) hide)
    )
    (property "Val" "33R" (id 6) (at 108.966 87.376 0))
    (property "License" "Apache-2.0" (id 7) (at 117.221 114.046 0)
      (effects (font (size 1.27 1.27) (thickness 0.15)) (justify left bottom) hide)
    )
    (property "Author" "Antmicro" (id 8) (at 117.221 116.586 0)
      (effects (font (size 1.27 1.27) (thickness 0.15)) (justify left bottom) hide)
    )
    (property "Tolerance" "1%" (id 9) (at 117.221 98.806 0)
      (effects (font (size 1.27 1.27)) (justify left bottom) hide)
    )
    (pin "1")
    (pin "2")
  )

  (symbol (lib_id "sa800u-baseboard-hw:R_1k_0402") (at 96.901 68.326 0) (unit 1)
    (in_bom yes) (on_board yes)
    (property "Reference" "R95" (id 0) (at 104.267 66.929 0)
      (effects (font (size 1.524 1.524)))
    )
    (property "Value" "R_1k_0402" (id 1) (at 96.901 72.136 0)
      (effects (font (size 1.524 1.524)) hide)
    )
    (property "Footprint" "sa800u-baseboard-hw-footprints:R_0402_1005Metric" (id 2) (at 101.981 63.246 0)
      (effects (font (size 1.524 1.524)) (justify left) hide)
    )
    (property "Datasheet" "https://www.bourns.com/docs/product-datasheets/cr.pdf" (id 3) (at 96.901 68.326 0)
      (effects (font (size 1.27 1.27)) hide)
    )
    (property "Manufacturer" "Bourns" (id 4) (at 101.981 58.166 0)
      (effects (font (size 1.524 1.524)) (justify left) hide)
    )
    (property "MPN" "CR0402-FX-1001GLF" (id 5) (at 101.981 60.706 0)
      (effects (font (size 1.524 1.524)) (justify left) hide)
    )
    (property "Val" "1k" (id 6) (at 108.331 67.056 0))
    (property "DNP" "DNP" (id 7) (at 99.441 68.326 0))
    (property "License" "Apache-2.0" (id 8) (at 117.221 93.726 0)
      (effects (font (size 1.27 1.27) (thickness 0.15)) (justify left bottom) hide)
    )
    (property "Author" "Antmicro" (id 9) (at 117.221 96.266 0)
      (effects (font (size 1.27 1.27) (thickness 0.15)) (justify left bottom) hide)
    )
    (property "Tolerance" "1%" (id 10) (at 117.221 78.486 0)
      (effects (font (size 1.27 1.27)) (justify left bottom) hide)
    )
    (pin "1")
    (pin "2")
  )

  (symbol (lib_id "sa800u-baseboard-hw:R_0R_0402") (at 96.901 78.486 0) (unit 1)
    (in_bom yes) (on_board yes)
    (property "Reference" "R99" (id 0) (at 104.267 77.089 0)
      (effects (font (size 1.524 1.524)))
    )
    (property "Value" "R_0R_0402" (id 1) (at 96.901 82.296 0)
      (effects (font (size 1.524 1.524)) hide)
    )
    (property "Footprint" "sa800u-baseboard-hw-footprints:R_0402_1005Metric" (id 2) (at 101.981 73.406 0)
      (effects (font (size 1.524 1.524)) (justify left) hide)
    )
    (property "Datasheet" "https://industrial.panasonic.com/cdbs/www-data/pdf/RDA0000/AOA0000C301.pdf" (id 3) (at 96.901 78.486 0)
      (effects (font (size 1.27 1.27)) hide)
    )
    (property "Manufacturer" "Panasonic" (id 4) (at 101.981 68.326 0)
      (effects (font (size 1.524 1.524)) (justify left) hide)
    )
    (property "MPN" "ERJ2GE0R00X" (id 5) (at 101.981 70.866 0)
      (effects (font (size 1.524 1.524)) (justify left) hide)
    )
    (property "Val" "0R" (id 6) (at 108.331 77.216 0))
    (property "License" "Apache-2.0" (id 7) (at 117.221 103.886 0)
      (effects (font (size 1.27 1.27) (thickness 0.15)) (justify left bottom) hide)
    )
    (property "Author" "Antmicro" (id 8) (at 117.221 106.426 0)
      (effects (font (size 1.27 1.27) (thickness 0.15)) (justify left bottom) hide)
    )
    (property "Tolerance" "~" (id 9) (at 117.221 88.646 0)
      (effects (font (size 1.27 1.27)) (justify left bottom) hide)
    )
    (property "Current" "1A" (id 10) (at 117.221 108.966 0)
      (effects (font (size 1.27 1.27) (thickness 0.15)) (justify left bottom) hide)
    )
    (pin "1")
    (pin "2")
  )

  (symbol (lib_id "sa800u-baseboard-hw:GND") (at 118.999 98.171 0) (unit 1)
    (in_bom yes) (on_board yes)
    (property "Reference" "#PWR0190" (id 0) (at 118.999 104.521 0)
      (effects (font (size 1.27 1.27)) hide)
    )
    (property "Value" "GND" (id 1) (at 119.126 102.5652 0))
    (property "Footprint" "" (id 2) (at 118.999 98.171 0)
      (effects (font (size 1.27 1.27)) hide)
    )
    (property "Datasheet" "" (id 3) (at 118.999 98.171 0)
      (effects (font (size 1.27 1.27)) hide)
    )
    (property "Author" "Antmicro" (id 4) (at 127.889 105.791 0)
      (effects (font (size 1.27 1.27) (thickness 0.15)) (justify left bottom) hide)
    )
    (property "License" "Apache-2.0" (id 5) (at 127.889 108.331 0)
      (effects (font (size 1.27 1.27) (thickness 0.15)) (justify left bottom) hide)
    )
    (pin "1")
  )

  (symbol (lib_id "sa800u-baseboard-hw:GND") (at 142.494 98.171 0) (unit 1)
    (in_bom yes) (on_board yes)
    (property "Reference" "#PWR0191" (id 0) (at 142.494 104.521 0)
      (effects (font (size 1.27 1.27)) hide)
    )
    (property "Value" "GND" (id 1) (at 142.621 102.5652 0))
    (property "Footprint" "" (id 2) (at 142.494 98.171 0)
      (effects (font (size 1.27 1.27)) hide)
    )
    (property "Datasheet" "" (id 3) (at 142.494 98.171 0)
      (effects (font (size 1.27 1.27)) hide)
    )
    (property "Author" "Antmicro" (id 4) (at 151.384 105.791 0)
      (effects (font (size 1.27 1.27) (thickness 0.15)) (justify left bottom) hide)
    )
    (property "License" "Apache-2.0" (id 5) (at 151.384 108.331 0)
      (effects (font (size 1.27 1.27) (thickness 0.15)) (justify left bottom) hide)
    )
    (pin "1")
  )

  (symbol (lib_id "sa800u-baseboard-hw:GND") (at 172.339 96.266 0) (unit 1)
    (in_bom yes) (on_board yes)
    (property "Reference" "#PWR0195" (id 0) (at 172.339 102.616 0)
      (effects (font (size 1.27 1.27)) hide)
    )
    (property "Value" "GND" (id 1) (at 172.466 100.6602 0))
    (property "Footprint" "" (id 2) (at 172.339 96.266 0)
      (effects (font (size 1.27 1.27)) hide)
    )
    (property "Datasheet" "" (id 3) (at 172.339 96.266 0)
      (effects (font (size 1.27 1.27)) hide)
    )
    (property "Author" "Antmicro" (id 4) (at 181.229 103.886 0)
      (effects (font (size 1.27 1.27) (thickness 0.15)) (justify left bottom) hide)
    )
    (property "License" "Apache-2.0" (id 5) (at 181.229 106.426 0)
      (effects (font (size 1.27 1.27) (thickness 0.15)) (justify left bottom) hide)
    )
    (pin "1")
  )

  (symbol (lib_id "sa800u-baseboard-hw:GND") (at 215.519 94.996 0) (unit 1)
    (in_bom yes) (on_board yes)
    (property "Reference" "#PWR0197" (id 0) (at 215.519 101.346 0)
      (effects (font (size 1.27 1.27)) hide)
    )
    (property "Value" "GND" (id 1) (at 215.646 99.3902 0))
    (property "Footprint" "" (id 2) (at 215.519 94.996 0)
      (effects (font (size 1.27 1.27)) hide)
    )
    (property "Datasheet" "" (id 3) (at 215.519 94.996 0)
      (effects (font (size 1.27 1.27)) hide)
    )
    (property "Author" "Antmicro" (id 4) (at 224.409 102.616 0)
      (effects (font (size 1.27 1.27) (thickness 0.15)) (justify left bottom) hide)
    )
    (property "License" "Apache-2.0" (id 5) (at 224.409 105.156 0)
      (effects (font (size 1.27 1.27) (thickness 0.15)) (justify left bottom) hide)
    )
    (pin "1")
  )

  (symbol (lib_id "sa800u-baseboard-hw:C_10p_0402") (at 154.559 57.531 270) (unit 1)
    (in_bom yes) (on_board yes) (fields_autoplaced)
    (property "Reference" "C118" (id 0) (at 157.734 58.8073 90)
      (effects (font (size 1.524 1.524)) (justify left))
    )
    (property "Value" "C_10p_0402" (id 1) (at 150.749 57.531 0)
      (effects (font (size 1.524 1.524)) hide)
    )
    (property "Footprint" "sa800u-baseboard-hw-footprints:C_0402_1005Metric" (id 2) (at 159.639 62.611 0)
      (effects (font (size 1.524 1.524)) (justify left) hide)
    )
    (property "Datasheet" "https://search.murata.co.jp/Ceramy/image/img/A01X/G101/ENG/GCM1555C1H100GA16-01.pdf" (id 3) (at 154.559 57.531 0)
      (effects (font (size 1.27 1.27)) hide)
    )
    (property "Manufacturer" "Murata" (id 4) (at 164.719 62.611 0)
      (effects (font (size 1.524 1.524)) (justify left) hide)
    )
    (property "MPN" "GCM1555C1H100GA16D" (id 5) (at 162.179 62.611 0)
      (effects (font (size 1.524 1.524)) (justify left) hide)
    )
    (property "Val" "10p" (id 6) (at 157.734 61.9822 90)
      (effects (font (size 1.27 1.27)) (justify left))
    )
    (property "License" "Apache-2.0" (id 7) (at 131.699 77.851 0)
      (effects (font (size 1.27 1.27) (thickness 0.15)) (justify left bottom) hide)
    )
    (property "Author" "Antmicro" (id 8) (at 129.159 77.851 0)
      (effects (font (size 1.27 1.27) (thickness 0.15)) (justify left bottom) hide)
    )
    (property "Voltage" "50V" (id 9) (at 126.619 77.851 0)
      (effects (font (size 1.27 1.27)) (justify left bottom) hide)
    )
    (property "Dielectric" "C0G" (id 10) (at 124.079 77.851 0)
      (effects (font (size 1.27 1.27)) (justify left bottom) hide)
    )
    (pin "1")
    (pin "2")
  )

  (symbol (lib_id "sa800u-baseboard-hw:C_2u2_0603") (at 165.354 57.531 270) (unit 1)
    (in_bom yes) (on_board yes) (fields_autoplaced)
    (property "Reference" "C119" (id 0) (at 167.894 58.8073 90)
      (effects (font (size 1.524 1.524)) (justify left))
    )
    (property "Value" "C_2u2_0603" (id 1) (at 161.544 57.531 0)
      (effects (font (size 1.524 1.524)) hide)
    )
    (property "Footprint" "sa800u-baseboard-hw-footprints:C_0603_1608Metric" (id 2) (at 170.434 62.611 0)
      (effects (font (size 1.524 1.524)) (justify left) hide)
    )
    (property "Datasheet" " " (id 3) (at 165.354 57.531 0)
      (effects (font (size 1.27 1.27)) hide)
    )
    (property "Manufacturer" "TDK" (id 4) (at 175.514 62.611 0)
      (effects (font (size 1.524 1.524)) (justify left) hide)
    )
    (property "MPN" "C1608X5R1V225K080AC" (id 5) (at 172.974 62.611 0)
      (effects (font (size 1.524 1.524)) (justify left) hide)
    )
    (property "Val" "2u2" (id 6) (at 167.894 61.9822 90)
      (effects (font (size 1.27 1.27)) (justify left))
    )
    (property "License" "Apache-2.0" (id 7) (at 142.494 77.851 0)
      (effects (font (size 1.27 1.27) (thickness 0.15)) (justify left bottom) hide)
    )
    (property "Author" "Antmicro" (id 8) (at 139.954 77.851 0)
      (effects (font (size 1.27 1.27) (thickness 0.15)) (justify left bottom) hide)
    )
    (property "Voltage" "" (id 9) (at 137.414 77.851 0)
      (effects (font (size 1.27 1.27)) (justify left bottom) hide)
    )
    (property "Dielectric" "" (id 10) (at 134.874 77.851 0)
      (effects (font (size 1.27 1.27)) (justify left bottom) hide)
    )
    (pin "1")
    (pin "2")
  )

  (symbol (lib_id "sa800u-baseboard-hw:GND") (at 154.559 62.611 0) (unit 1)
    (in_bom yes) (on_board yes)
    (property "Reference" "#PWR0193" (id 0) (at 154.559 68.961 0)
      (effects (font (size 1.27 1.27)) hide)
    )
    (property "Value" "GND" (id 1) (at 154.686 67.0052 0))
    (property "Footprint" "" (id 2) (at 154.559 62.611 0)
      (effects (font (size 1.27 1.27)) hide)
    )
    (property "Datasheet" "" (id 3) (at 154.559 62.611 0)
      (effects (font (size 1.27 1.27)) hide)
    )
    (property "Author" "Antmicro" (id 4) (at 163.449 70.231 0)
      (effects (font (size 1.27 1.27) (thickness 0.15)) (justify left bottom) hide)
    )
    (property "License" "Apache-2.0" (id 5) (at 163.449 72.771 0)
      (effects (font (size 1.27 1.27) (thickness 0.15)) (justify left bottom) hide)
    )
    (pin "1")
  )

  (symbol (lib_id "sa800u-baseboard-hw:GND") (at 165.354 62.611 0) (unit 1)
    (in_bom yes) (on_board yes)
    (property "Reference" "#PWR0194" (id 0) (at 165.354 68.961 0)
      (effects (font (size 1.27 1.27)) hide)
    )
    (property "Value" "GND" (id 1) (at 165.481 67.0052 0))
    (property "Footprint" "" (id 2) (at 165.354 62.611 0)
      (effects (font (size 1.27 1.27)) hide)
    )
    (property "Datasheet" "" (id 3) (at 165.354 62.611 0)
      (effects (font (size 1.27 1.27)) hide)
    )
    (property "Author" "Antmicro" (id 4) (at 174.244 70.231 0)
      (effects (font (size 1.27 1.27) (thickness 0.15)) (justify left bottom) hide)
    )
    (property "License" "Apache-2.0" (id 5) (at 174.244 72.771 0)
      (effects (font (size 1.27 1.27) (thickness 0.15)) (justify left bottom) hide)
    )
    (pin "1")
  )

  (symbol (lib_id "sa800u-baseboard-hw:R_100k_0402") (at 92.329 59.436 270) (unit 1)
    (in_bom yes) (on_board yes)
    (property "Reference" "R94" (id 0) (at 93.599 60.579 90)
      (effects (font (size 1.524 1.524)) (justify left))
    )
    (property "Value" "R_100k_0402" (id 1) (at 88.519 59.436 0)
      (effects (font (size 1.524 1.524)) hide)
    )
    (property "Footprint" "sa800u-baseboard-hw-footprints:R_0402_1005Metric" (id 2) (at 97.409 64.516 0)
      (effects (font (size 1.524 1.524)) (justify left) hide)
    )
    (property "Datasheet" "https://www.bourns.com/docs/product-datasheets/cr.pdf" (id 3) (at 92.329 59.436 0)
      (effects (font (size 1.27 1.27)) hide)
    )
    (property "Manufacturer" "Bourns" (id 4) (at 102.489 64.516 0)
      (effects (font (size 1.524 1.524)) (justify left) hide)
    )
    (property "MPN" "CR0402-FX-1003GLF" (id 5) (at 99.949 64.516 0)
      (effects (font (size 1.524 1.524)) (justify left) hide)
    )
    (property "Val" "100k" (id 6) (at 93.599 63.0682 90)
      (effects (font (size 1.27 1.27)) (justify left))
    )
    (property "DNP" "DNP" (id 7) (at 92.456 59.944 0)
      (effects (font (size 1.27 1.27)) (justify left))
    )
    (property "License" "Apache-2.0" (id 8) (at 66.929 79.756 0)
      (effects (font (size 1.27 1.27) (thickness 0.15)) (justify left bottom) hide)
    )
    (property "Author" "Antmicro" (id 9) (at 64.389 79.756 0)
      (effects (font (size 1.27 1.27) (thickness 0.15)) (justify left bottom) hide)
    )
    (property "Tolerance" "1%" (id 10) (at 82.169 79.756 0)
      (effects (font (size 1.27 1.27)) (justify left bottom) hide)
    )
    (pin "1")
    (pin "2")
  )

  (symbol (lib_id "sa800u-baseboard-hw:PUSB3F96X_PASS") (at 136.779 94.996 270) (unit 1)
    (in_bom yes) (on_board yes) (fields_autoplaced)
    (property "Reference" "D22" (id 0) (at 131.699 110.871 90)
      (effects (font (size 1.524 1.524)))
    )
    (property "Value" "PUSB3F96X_PASS" (id 1) (at 131.699 114.681 90)
      (effects (font (size 1.524 1.524)))
    )
    (property "Footprint" "sa800u-baseboard-hw-footprints:Nexperia_DFN-10_2.5x1mm_P0.5mm" (id 2) (at 122.809 100.076 0)
      (effects (font (size 1.524 1.524)) hide)
    )
    (property "Datasheet" "https://pl.mouser.com/datasheet/2/916/PUSB3F96-1600324.pdf" (id 3) (at 136.779 94.996 0)
      (effects (font (size 1.524 1.524)) hide)
    )
    (property "Manufacturer" "Nexperia" (id 4) (at 120.269 100.076 0)
      (effects (font (size 1.27 1.27)) hide)
    )
    (property "MPN" "PUSB3F96X" (id 5) (at 120.269 100.076 0)
      (effects (font (size 1.27 1.27)) hide)
    )
    (property "Author" "Antmicro" (id 6) (at 118.999 120.396 0)
      (effects (font (size 1.27 1.27) (thickness 0.15)) (justify left bottom) hide)
    )
    (property "License" "Apache-2.0" (id 7) (at 116.459 120.396 0)
      (effects (font (size 1.27 1.27) (thickness 0.15)) (justify left bottom) hide)
    )
    (pin "1")
    (pin "10")
    (pin "2")
    (pin "3")
    (pin "4")
    (pin "5")
    (pin "6")
    (pin "7")
    (pin "8")
    (pin "9")
  )

  (symbol (lib_id "sa800u-baseboard-hw:PUSB3F96X_PASS") (at 160.274 94.996 270) (unit 1)
    (in_bom yes) (on_board yes) (fields_autoplaced)
    (property "Reference" "D23" (id 0) (at 155.194 110.871 90)
      (effects (font (size 1.524 1.524)))
    )
    (property "Value" "PUSB3F96X_PASS" (id 1) (at 155.194 114.681 90)
      (effects (font (size 1.524 1.524)))
    )
    (property "Footprint" "sa800u-baseboard-hw-footprints:Nexperia_DFN-10_2.5x1mm_P0.5mm" (id 2) (at 146.304 100.076 0)
      (effects (font (size 1.524 1.524)) hide)
    )
    (property "Datasheet" "https://pl.mouser.com/datasheet/2/916/PUSB3F96-1600324.pdf" (id 3) (at 160.274 94.996 0)
      (effects (font (size 1.524 1.524)) hide)
    )
    (property "Manufacturer" "Nexperia" (id 4) (at 143.764 100.076 0)
      (effects (font (size 1.27 1.27)) hide)
    )
    (property "MPN" "PUSB3F96X" (id 5) (at 143.764 100.076 0)
      (effects (font (size 1.27 1.27)) hide)
    )
    (property "Author" "Antmicro" (id 6) (at 142.494 120.396 0)
      (effects (font (size 1.27 1.27) (thickness 0.15)) (justify left bottom) hide)
    )
    (property "License" "Apache-2.0" (id 7) (at 139.954 120.396 0)
      (effects (font (size 1.27 1.27) (thickness 0.15)) (justify left bottom) hide)
    )
    (pin "1")
    (pin "10")
    (pin "2")
    (pin "3")
    (pin "4")
    (pin "5")
    (pin "6")
    (pin "7")
    (pin "8")
    (pin "9")
  )

  (symbol (lib_id "sa800u-baseboard-hw:DM3AT-SF-PEJM5") (at 173.609 70.866 0) (unit 1)
    (in_bom yes) (on_board yes) (fields_autoplaced)
    (property "Reference" "J8" (id 0) (at 195.834 58.674 0))
    (property "Value" "DM3AT-SF-PEJM5" (id 1) (at 172.339 47.8028 0)
      (effects (font (size 1.27 1.27)) hide)
    )
    (property "Footprint" "sa800u-baseboard-hw-footprints:MicroSD_DM3AT-SF-PEJM5" (id 2) (at 173.609 70.866 0)
      (effects (font (size 1.27 1.27)) hide)
    )
    (property "Datasheet" "https://www.hirose.com/en/product/document?clcode=CL0609-0031-0-00&productname=DM3AT-SF-PEJM5&series=DM3&documenttype=2DDrawing&lang=en&documentid=0000947170" (id 3) (at 173.609 70.866 0)
      (effects (font (size 1.27 1.27)) hide)
    )
    (property "Manufacturer" "Hirose" (id 4) (at 172.339 50.1142 0)
      (effects (font (size 1.27 1.27)) hide)
    )
    (property "MPN" "DM3AT-SF-PEJM5" (id 5) (at 195.834 61.214 0))
    (property "Author" "Antmicro" (id 6) (at 230.759 86.106 0)
      (effects (font (size 1.27 1.27) (thickness 0.15)) (justify left bottom) hide)
    )
    (property "License" "Apache-2.0" (id 7) (at 230.759 88.646 0)
      (effects (font (size 1.27 1.27) (thickness 0.15)) (justify left bottom) hide)
    )
    (pin "1")
    (pin "10")
    (pin "11")
    (pin "2")
    (pin "3")
    (pin "4")
    (pin "5")
    (pin "6")
    (pin "7")
    (pin "8")
    (pin "9")
  )

  (symbol (lib_id "sa800u-baseboard-hw:BM04B-SRSS-TB-LF-SN") (at 224.917 157.607 0) (mirror x) (unit 1)
    (in_bom yes) (on_board yes) (fields_autoplaced)
    (property "Reference" "J9" (id 0) (at 228.727 141.097 0))
    (property "Value" "BM04B-SRSS-TB-LF-SN" (id 1) (at 222.8342 152.9334 0)
      (effects (font (size 1.27 1.27)) hide)
    )
    (property "Footprint" "sa800u-baseboard-hw-footprints:BM04B-SRSS-TB-LF-SN" (id 2) (at 224.917 151.257 0)
      (effects (font (size 1.27 1.27)) hide)
    )
    (property "Datasheet" "https://www.jst-mfg.com/product/pdf/eng/eSH.pdf" (id 3) (at 213.487 149.987 0)
      (effects (font (size 1.27 1.27)) hide)
    )
    (property "MPN" "BM04B-SRSS-TB(LF)(SN) " (id 4) (at 228.727 143.637 0))
    (property "Manufacturer" "JST" (id 5) (at 222.377 146.177 0)
      (effects (font (size 1.27 1.27)) (justify left) hide)
    )
    (property "Author" "Antmicro" (id 6) (at 245.237 137.287 0)
      (effects (font (size 1.27 1.27) (thickness 0.15)) (justify left bottom) hide)
    )
    (property "License" "Apache-2.0" (id 7) (at 245.237 134.747 0)
      (effects (font (size 1.27 1.27) (thickness 0.15)) (justify left bottom) hide)
    )
    (pin "1")
    (pin "2")
    (pin "3")
    (pin "4")
    (pin "MP")
  )

  (symbol (lib_id "sa800u-baseboard-hw:NTS0102_XSON") (at 120.142 155.702 0) (unit 1)
    (in_bom yes) (on_board yes) (fields_autoplaced)
    (property "Reference" "U16" (id 0) (at 130.302 147.447 0))
    (property "Value" "NTS0102_XSON" (id 1) (at 120.142 144.9324 0)
      (effects (font (size 1.27 1.27)) hide)
    )
    (property "Footprint" "sa800u-baseboard-hw-footprints:XSON-8_1x1.95mm_P0.5mm" (id 2) (at 117.602 143.002 0)
      (effects (font (size 1.27 1.27)) hide)
    )
    (property "Datasheet" "http://www.farnell.com/datasheets/1760723.pdf" (id 3) (at 136.652 136.652 0)
      (effects (font (size 1.27 1.27)) hide)
    )
    (property "MPN" "NTS0102GT" (id 4) (at 130.302 149.987 0))
    (property "Manufacturer" "NXP" (id 5) (at 120.142 144.9324 0)
      (effects (font (size 1.27 1.27)) hide)
    )
    (property "Author" "Antmicro" (id 6) (at 155.702 173.482 0)
      (effects (font (size 1.27 1.27) (thickness 0.15)) (justify left bottom) hide)
    )
    (property "License" "Apache-2.0" (id 7) (at 155.702 176.022 0)
      (effects (font (size 1.27 1.27) (thickness 0.15)) (justify left bottom) hide)
    )
    (pin "1")
    (pin "2")
    (pin "3")
    (pin "4")
    (pin "5")
    (pin "6")
    (pin "7")
    (pin "8")
  )

  (symbol (lib_id "sa800u-baseboard-hw:C_100n_0402") (at 84.582 149.352 270) (unit 1)
    (in_bom yes) (on_board yes) (fields_autoplaced)
    (property "Reference" "C117" (id 0) (at 87.757 150.6283 90)
      (effects (font (size 1.524 1.524)) (justify left))
    )
    (property "Value" "C_100n_0402" (id 1) (at 80.772 149.352 0)
      (effects (font (size 1.524 1.524)) hide)
    )
    (property "Footprint" "sa800u-baseboard-hw-footprints:C_0402_1005Metric" (id 2) (at 89.662 154.432 0)
      (effects (font (size 1.524 1.524)) (justify left) hide)
    )
    (property "Datasheet" "https://search.murata.co.jp/Ceramy/image/img/A01X/G101/ENG/GRM155R61H104KE14-01.pdf" (id 3) (at 84.582 149.352 0)
      (effects (font (size 1.27 1.27)) hide)
    )
    (property "Manufacturer" "Murata" (id 4) (at 94.742 154.432 0)
      (effects (font (size 1.524 1.524)) (justify left) hide)
    )
    (property "MPN" "GRM155R61H104KE14D" (id 5) (at 92.202 154.432 0)
      (effects (font (size 1.524 1.524)) (justify left) hide)
    )
    (property "Val" "100n" (id 6) (at 87.757 153.8032 90)
      (effects (font (size 1.27 1.27)) (justify left))
    )
    (property "License" "Apache-2.0" (id 7) (at 61.722 169.672 0)
      (effects (font (size 1.27 1.27) (thickness 0.15)) (justify left bottom) hide)
    )
    (property "Author" "Antmicro" (id 8) (at 59.182 169.672 0)
      (effects (font (size 1.27 1.27) (thickness 0.15)) (justify left bottom) hide)
    )
    (property "Voltage" "50V" (id 9) (at 56.642 169.672 0)
      (effects (font (size 1.27 1.27)) (justify left bottom) hide)
    )
    (property "Dielectric" "X5R" (id 10) (at 54.102 169.672 0)
      (effects (font (size 1.27 1.27)) (justify left bottom) hide)
    )
    (pin "1")
    (pin "2")
  )

  (symbol (lib_id "sa800u-baseboard-hw:GND") (at 84.582 154.432 0) (unit 1)
    (in_bom yes) (on_board yes)
    (property "Reference" "#PWR0189" (id 0) (at 84.582 160.782 0)
      (effects (font (size 1.27 1.27)) hide)
    )
    (property "Value" "GND" (id 1) (at 84.709 158.8262 0))
    (property "Footprint" "" (id 2) (at 84.582 154.432 0)
      (effects (font (size 1.27 1.27)) hide)
    )
    (property "Datasheet" "" (id 3) (at 84.582 154.432 0)
      (effects (font (size 1.27 1.27)) hide)
    )
    (property "Author" "Antmicro" (id 4) (at 93.472 162.052 0)
      (effects (font (size 1.27 1.27) (thickness 0.15)) (justify left bottom) hide)
    )
    (property "License" "Apache-2.0" (id 5) (at 93.472 164.592 0)
      (effects (font (size 1.27 1.27) (thickness 0.15)) (justify left bottom) hide)
    )
    (pin "1")
  )

  (symbol (lib_id "sa800u-baseboard-hw:C_100n_0402") (at 176.022 149.352 90) (mirror x) (unit 1)
    (in_bom yes) (on_board yes) (fields_autoplaced)
    (property "Reference" "C120" (id 0) (at 179.197 150.6283 90)
      (effects (font (size 1.524 1.524)) (justify right))
    )
    (property "Value" "C_100n_0402" (id 1) (at 179.832 149.352 0)
      (effects (font (size 1.524 1.524)) hide)
    )
    (property "Footprint" "sa800u-baseboard-hw-footprints:C_0402_1005Metric" (id 2) (at 170.942 154.432 0)
      (effects (font (size 1.524 1.524)) (justify left) hide)
    )
    (property "Datasheet" "https://search.murata.co.jp/Ceramy/image/img/A01X/G101/ENG/GRM155R61H104KE14-01.pdf" (id 3) (at 176.022 149.352 0)
      (effects (font (size 1.27 1.27)) hide)
    )
    (property "Manufacturer" "Murata" (id 4) (at 165.862 154.432 0)
      (effects (font (size 1.524 1.524)) (justify left) hide)
    )
    (property "MPN" "GRM155R61H104KE14D" (id 5) (at 168.402 154.432 0)
      (effects (font (size 1.524 1.524)) (justify left) hide)
    )
    (property "Val" "100n" (id 6) (at 179.197 153.8032 90)
      (effects (font (size 1.27 1.27)) (justify right))
    )
    (property "License" "Apache-2.0" (id 7) (at 198.882 169.672 0)
      (effects (font (size 1.27 1.27) (thickness 0.15)) (justify left bottom) hide)
    )
    (property "Author" "Antmicro" (id 8) (at 201.422 169.672 0)
      (effects (font (size 1.27 1.27) (thickness 0.15)) (justify left bottom) hide)
    )
    (property "Voltage" "50V" (id 9) (at 203.962 169.672 0)
      (effects (font (size 1.27 1.27)) (justify left bottom) hide)
    )
    (property "Dielectric" "X5R" (id 10) (at 206.502 169.672 0)
      (effects (font (size 1.27 1.27)) (justify left bottom) hide)
    )
    (pin "1")
    (pin "2")
  )

  (symbol (lib_id "sa800u-baseboard-hw:GND") (at 176.022 154.432 0) (mirror y) (unit 1)
    (in_bom yes) (on_board yes)
    (property "Reference" "#PWR0196" (id 0) (at 176.022 160.782 0)
      (effects (font (size 1.27 1.27)) hide)
    )
    (property "Value" "GND" (id 1) (at 175.895 158.8262 0))
    (property "Footprint" "" (id 2) (at 176.022 154.432 0)
      (effects (font (size 1.27 1.27)) hide)
    )
    (property "Datasheet" "" (id 3) (at 176.022 154.432 0)
      (effects (font (size 1.27 1.27)) hide)
    )
    (property "Author" "Antmicro" (id 4) (at 167.132 162.052 0)
      (effects (font (size 1.27 1.27) (thickness 0.15)) (justify left bottom) hide)
    )
    (property "License" "Apache-2.0" (id 5) (at 167.132 164.592 0)
      (effects (font (size 1.27 1.27) (thickness 0.15)) (justify left bottom) hide)
    )
    (pin "1")
  )

  (symbol (lib_id "sa800u-baseboard-hw:GND") (at 141.732 164.592 0) (mirror y) (unit 1)
    (in_bom yes) (on_board yes)
    (property "Reference" "#PWR0192" (id 0) (at 141.732 170.942 0)
      (effects (font (size 1.27 1.27)) hide)
    )
    (property "Value" "GND" (id 1) (at 141.605 168.9862 0))
    (property "Footprint" "" (id 2) (at 141.732 164.592 0)
      (effects (font (size 1.27 1.27)) hide)
    )
    (property "Datasheet" "" (id 3) (at 141.732 164.592 0)
      (effects (font (size 1.27 1.27)) hide)
    )
    (property "Author" "Antmicro" (id 4) (at 132.842 172.212 0)
      (effects (font (size 1.27 1.27) (thickness 0.15)) (justify left bottom) hide)
    )
    (property "License" "Apache-2.0" (id 5) (at 132.842 174.752 0)
      (effects (font (size 1.27 1.27) (thickness 0.15)) (justify left bottom) hide)
    )
    (pin "1")
  )

  (symbol (lib_id "sa800u-baseboard-hw:R_2k_0402") (at 152.527 154.178 270) (mirror x) (unit 1)
    (in_bom yes) (on_board yes)
    (property "Reference" "R103" (id 0) (at 150.749 153.035 90)
      (effects (font (size 1.524 1.524)) (justify right))
    )
    (property "Value" "R_2k_0402" (id 1) (at 148.717 154.178 0)
      (effects (font (size 1.524 1.524)) hide)
    )
    (property "Footprint" "sa800u-baseboard-hw-footprints:R_0402_1005Metric" (id 2) (at 157.607 149.098 0)
      (effects (font (size 1.524 1.524)) (justify left) hide)
    )
    (property "Datasheet" "https://www.bourns.com/docs/product-datasheets/cr.pdf" (id 3) (at 152.527 154.178 0)
      (effects (font (size 1.27 1.27)) hide)
    )
    (property "Manufacturer" "Bourns" (id 4) (at 162.687 149.098 0)
      (effects (font (size 1.524 1.524)) (justify left) hide)
    )
    (property "MPN" "CR0402-FX-2001GLF" (id 5) (at 160.147 149.098 0)
      (effects (font (size 1.524 1.524)) (justify left) hide)
    )
    (property "Val" "2k" (id 6) (at 150.749 155.5242 90)
      (effects (font (size 1.27 1.27)) (justify right))
    )
    (property "License" "Apache-2.0" (id 7) (at 127.127 133.858 0)
      (effects (font (size 1.27 1.27) (thickness 0.15)) (justify left bottom) hide)
    )
    (property "Author" "Antmicro" (id 8) (at 124.587 133.858 0)
      (effects (font (size 1.27 1.27) (thickness 0.15)) (justify left bottom) hide)
    )
    (property "Tolerance" "1%" (id 9) (at 142.367 133.858 0)
      (effects (font (size 1.27 1.27)) (justify left bottom) hide)
    )
    (pin "1")
    (pin "2")
  )

  (symbol (lib_id "sa800u-baseboard-hw:R_2k_0402") (at 155.067 154.178 270) (mirror x) (unit 1)
    (in_bom yes) (on_board yes)
    (property "Reference" "R104" (id 0) (at 156.8196 153.035 90)
      (effects (font (size 1.524 1.524)) (justify left))
    )
    (property "Value" "R_2k_0402" (id 1) (at 151.257 154.178 0)
      (effects (font (size 1.524 1.524)) hide)
    )
    (property "Footprint" "sa800u-baseboard-hw-footprints:R_0402_1005Metric" (id 2) (at 160.147 149.098 0)
      (effects (font (size 1.524 1.524)) (justify left) hide)
    )
    (property "Datasheet" "https://www.bourns.com/docs/product-datasheets/cr.pdf" (id 3) (at 155.067 154.178 0)
      (effects (font (size 1.27 1.27)) hide)
    )
    (property "Manufacturer" "Bourns" (id 4) (at 165.227 149.098 0)
      (effects (font (size 1.524 1.524)) (justify left) hide)
    )
    (property "MPN" "CR0402-FX-2001GLF" (id 5) (at 162.687 149.098 0)
      (effects (font (size 1.524 1.524)) (justify left) hide)
    )
    (property "Val" "2k" (id 6) (at 156.8196 155.5242 90)
      (effects (font (size 1.27 1.27)) (justify left))
    )
    (property "License" "Apache-2.0" (id 7) (at 129.667 133.858 0)
      (effects (font (size 1.27 1.27) (thickness 0.15)) (justify left bottom) hide)
    )
    (property "Author" "Antmicro" (id 8) (at 127.127 133.858 0)
      (effects (font (size 1.27 1.27) (thickness 0.15)) (justify left bottom) hide)
    )
    (property "Tolerance" "1%" (id 9) (at 144.907 133.858 0)
      (effects (font (size 1.27 1.27)) (justify left bottom) hide)
    )
    (pin "1")
    (pin "2")
  )

  (symbol (lib_id "sa800u-baseboard-hw:TP_0.75mm_SMD") (at 155.067 163.322 90) (mirror x) (unit 1)
    (in_bom yes) (on_board yes) (fields_autoplaced)
    (property "Reference" "TP47" (id 0) (at 157.607 166.4969 90)
      (effects (font (size 1.27 1.27)) (justify right))
    )
    (property "Value" "TP_0.75mm_SMD" (id 1) (at 157.607 163.322 0)
      (effects (font (size 1.27 1.27)) hide)
    )
    (property "Footprint" "sa800u-baseboard-hw-footprints:TP_SMD_0.75mm" (id 2) (at 149.987 168.402 0)
      (effects (font (size 1.524 1.524)) (justify left) hide)
    )
    (property "Datasheet" "" (id 3) (at 147.447 168.402 0)
      (effects (font (size 1.524 1.524)) (justify left) hide)
    )
    (property "MPN" "" (id 4) (at 170.307 181.102 0)
      (effects (font (size 1.27 1.27) (thickness 0.15)) (justify left bottom) hide)
    )
    (property "Manufacturer" "" (id 5) (at 172.847 181.102 0)
      (effects (font (size 1.27 1.27) (thickness 0.15)) (justify left bottom) hide)
    )
    (property "Author" "Antmicro" (id 6) (at 175.387 181.102 0)
      (effects (font (size 1.27 1.27) (thickness 0.15)) (justify left bottom) hide)
    )
    (property "License" "Apache-2.0" (id 7) (at 177.927 181.102 0)
      (effects (font (size 1.27 1.27) (thickness 0.15)) (justify left bottom) hide)
    )
    (pin "1")
  )

  (symbol (lib_id "sa800u-baseboard-hw:TP_0.75mm_SMD") (at 152.527 163.322 90) (mirror x) (unit 1)
    (in_bom yes) (on_board yes) (fields_autoplaced)
    (property "Reference" "TP46" (id 0) (at 149.987 166.4969 90)
      (effects (font (size 1.27 1.27)) (justify left))
    )
    (property "Value" "TP_0.75mm_SMD" (id 1) (at 155.067 163.322 0)
      (effects (font (size 1.27 1.27)) hide)
    )
    (property "Footprint" "sa800u-baseboard-hw-footprints:TP_SMD_0.75mm" (id 2) (at 147.447 168.402 0)
      (effects (font (size 1.524 1.524)) (justify left) hide)
    )
    (property "Datasheet" "" (id 3) (at 144.907 168.402 0)
      (effects (font (size 1.524 1.524)) (justify left) hide)
    )
    (property "MPN" "" (id 4) (at 167.767 181.102 0)
      (effects (font (size 1.27 1.27) (thickness 0.15)) (justify left bottom) hide)
    )
    (property "Manufacturer" "" (id 5) (at 170.307 181.102 0)
      (effects (font (size 1.27 1.27) (thickness 0.15)) (justify left bottom) hide)
    )
    (property "Author" "Antmicro" (id 6) (at 172.847 181.102 0)
      (effects (font (size 1.27 1.27) (thickness 0.15)) (justify left bottom) hide)
    )
    (property "License" "Apache-2.0" (id 7) (at 175.387 181.102 0)
      (effects (font (size 1.27 1.27) (thickness 0.15)) (justify left bottom) hide)
    )
    (pin "1")
  )

  (symbol (lib_id "sa800u-baseboard-hw:TP_0.75mm_SMD") (at 105.537 163.322 270) (unit 1)
    (in_bom yes) (on_board yes) (fields_autoplaced)
    (property "Reference" "TP44" (id 0) (at 102.997 166.4969 90)
      (effects (font (size 1.27 1.27)) (justify right))
    )
    (property "Value" "TP_0.75mm_SMD" (id 1) (at 102.997 163.322 0)
      (effects (font (size 1.27 1.27)) hide)
    )
    (property "Footprint" "sa800u-baseboard-hw-footprints:TP_SMD_0.75mm" (id 2) (at 110.617 168.402 0)
      (effects (font (size 1.524 1.524)) (justify left) hide)
    )
    (property "Datasheet" "" (id 3) (at 113.157 168.402 0)
      (effects (font (size 1.524 1.524)) (justify left) hide)
    )
    (property "MPN" "" (id 4) (at 90.297 181.102 0)
      (effects (font (size 1.27 1.27) (thickness 0.15)) (justify left bottom) hide)
    )
    (property "Manufacturer" "" (id 5) (at 87.757 181.102 0)
      (effects (font (size 1.27 1.27) (thickness 0.15)) (justify left bottom) hide)
    )
    (property "Author" "Antmicro" (id 6) (at 85.217 181.102 0)
      (effects (font (size 1.27 1.27) (thickness 0.15)) (justify left bottom) hide)
    )
    (property "License" "Apache-2.0" (id 7) (at 82.677 181.102 0)
      (effects (font (size 1.27 1.27) (thickness 0.15)) (justify left bottom) hide)
    )
    (pin "1")
  )

  (symbol (lib_id "sa800u-baseboard-hw:TP_0.75mm_SMD") (at 108.077 163.322 270) (unit 1)
    (in_bom yes) (on_board yes) (fields_autoplaced)
    (property "Reference" "TP45" (id 0) (at 110.617 166.4969 90)
      (effects (font (size 1.27 1.27)) (justify left))
    )
    (property "Value" "TP_0.75mm_SMD" (id 1) (at 105.537 163.322 0)
      (effects (font (size 1.27 1.27)) hide)
    )
    (property "Footprint" "sa800u-baseboard-hw-footprints:TP_SMD_0.75mm" (id 2) (at 113.157 168.402 0)
      (effects (font (size 1.524 1.524)) (justify left) hide)
    )
    (property "Datasheet" "" (id 3) (at 115.697 168.402 0)
      (effects (font (size 1.524 1.524)) (justify left) hide)
    )
    (property "MPN" "" (id 4) (at 92.837 181.102 0)
      (effects (font (size 1.27 1.27) (thickness 0.15)) (justify left bottom) hide)
    )
    (property "Manufacturer" "" (id 5) (at 90.297 181.102 0)
      (effects (font (size 1.27 1.27) (thickness 0.15)) (justify left bottom) hide)
    )
    (property "Author" "Antmicro" (id 6) (at 87.757 181.102 0)
      (effects (font (size 1.27 1.27) (thickness 0.15)) (justify left bottom) hide)
    )
    (property "License" "Apache-2.0" (id 7) (at 85.217 181.102 0)
      (effects (font (size 1.27 1.27) (thickness 0.15)) (justify left bottom) hide)
    )
    (pin "1")
  )

  (symbol (lib_id "sa800u-baseboard-hw:GND") (at 223.647 158.877 0) (mirror y) (unit 1)
    (in_bom yes) (on_board yes)
    (property "Reference" "#PWR0198" (id 0) (at 223.647 165.227 0)
      (effects (font (size 1.27 1.27)) hide)
    )
    (property "Value" "GND" (id 1) (at 223.52 163.2712 0))
    (property "Footprint" "" (id 2) (at 223.647 158.877 0)
      (effects (font (size 1.27 1.27)) hide)
    )
    (property "Datasheet" "" (id 3) (at 223.647 158.877 0)
      (effects (font (size 1.27 1.27)) hide)
    )
    (property "Author" "Antmicro" (id 4) (at 214.757 166.497 0)
      (effects (font (size 1.27 1.27) (thickness 0.15)) (justify left bottom) hide)
    )
    (property "License" "Apache-2.0" (id 5) (at 214.757 169.037 0)
      (effects (font (size 1.27 1.27) (thickness 0.15)) (justify left bottom) hide)
    )
    (pin "1")
  )

  (symbol (lib_id "sa800u-baseboard-hw:PWR_FLAG") (at 154.559 54.356 0) (unit 1)
    (in_bom yes) (on_board yes)
    (property "Reference" "#FLG0107" (id 0) (at 154.559 52.451 0)
      (effects (font (size 1.27 1.27)) hide)
    )
    (property "Value" "PWR_FLAG" (id 1) (at 154.559 50.8 0))
    (property "Footprint" "" (id 2) (at 154.559 54.356 0)
      (effects (font (size 1.27 1.27)) hide)
    )
    (property "Datasheet" "~" (id 3) (at 154.559 54.356 0)
      (effects (font (size 1.27 1.27)) hide)
    )
    (pin "1")
  )
)
